# SCM (Grand Teton) — schematic netlist excerpt (pin names and nets, part order shuffled) for the footprints in the layout excerpt that follows; sources: Cadence DE-HDL packaged netlist, KiCad conversion of 12092022_DA0F0TMDCD0_F0T_Management_Board_D_brd_V3_OCP.brd

C59  Q_CAP  0.1UF 25V 10% X7R  pkg 0402  page 16 : A = P1V0_STBY_PLAVDD ; B = GND
R344  Q_RES  120 1% CHIP  pkg 0402LF  page 20 : A = GND ; B = M_BMC_DDR4_MACT_N

(kicad_pcb
	(version 20260206)
	(generator "pcbnew")
	(generator_version "10.0")
	(general
		(thickness 1.6)
		(legacy_teardrops no)
	)
	(paper "A4")
	(title_block
		(title "12092022_DA0F0TMDCD0_F0T_Management_Board_D_brd_V3_OCP.brd")
		(comment 1 "Grand Teton / footprints 781-782 of 1440")
	)
	(layers
		(0 "F.Cu" signal "TOP")
		(4 "In1.Cu" signal "GND")
		(6 "In2.Cu" signal "IN1")
		(8 "In3.Cu" signal "GND1")
		(10 "In4.Cu" signal "IN2")
		(12 "In5.Cu" signal "VCC")
		(14 "In6.Cu" signal "VCC1")
		(16 "In7.Cu" signal "IN3")
		(18 "In8.Cu" signal "GND2")
		(20 "In9.Cu" signal "IN4")
		(22 "In10.Cu" signal "GND3")
		(2 "B.Cu" signal "BOTTOM")
		(9 "F.Adhes" user "F.Adhesive")
		(11 "B.Adhes" user "B.Adhesive")
		(13 "F.Paste" user "Package Geometry/Pastemask Top")
		(15 "B.Paste" user "Package Geometry/Pastemask Bottom")
		(5 "F.SilkS" user "Ref Des/Silkscreen Top")
		(7 "B.SilkS" user "Ref Des/Silkscreen Bottom")
		(1 "F.Mask" user "Board Geometry/Soldermask Top")
		(3 "B.Mask" user "Board Geometry/Soldermask Bottom")
		(17 "Dwgs.User" user "User.Drawings")
		(19 "Cmts.User" user "User.Comments")
		(21 "Eco1.User" user "User.Eco1")
		(23 "Eco2.User" user "User.Eco2")
		(25 "Edge.Cuts" user "Board Geometry/Outline")
		(27 "Margin" user)
		(31 "F.CrtYd" user "Package Geometry/Place Bound Top")
		(29 "B.CrtYd" user "Package Geometry/Place Bound Bottom")
		(35 "F.Fab" user "Ref Des/Assembly Top")
		(33 "B.Fab" user "Ref Des/Assembly Bottom")
	)
	(footprint ""
		(layer "B.Cu")
		(at 81.129886 -40.990012)
		(property "Reference" "R344"
			(at 0 0 0)
			(layer "B.SilkS")
			(hide yes)
			(effects
				(font
					(size 1.27 1.27)
				)
				(justify mirror)
			)
		)
		(property "Value" ""
			(at 0 0 0)
			(layer "B.Fab")
			(effects
				(font
					(size 1.27 1.27)
				)
				(justify mirror)
			)
		)
		(duplicate_pad_numbers_are_jumpers no)
		(fp_line
			(start -0.7874 -0.4064)
			(end -0.7874 0.4064)
			(stroke
				(width 0.1524)
				(type default)
			)
			(layer "B.SilkS")
		)
		(fp_line
			(start -0.7874 0.4064)
			(end 0.7874 0.4064)
			(stroke
				(width 0.1524)
				(type default)
			)
			(layer "B.SilkS")
		)
		(fp_line
			(start 0.7874 -0.4064)
			(end -0.7874 -0.4064)
			(stroke
				(width 0.1524)
				(type default)
			)
			(layer "B.SilkS")
		)
		(fp_line
			(start 0.7874 0.4064)
			(end 0.7874 -0.4064)
			(stroke
				(width 0.1524)
				(type default)
			)
			(layer "B.SilkS")
		)
		(fp_line
			(start -0.67945 -0.3048)
			(end -0.67945 0.3048)
			(stroke
				(width 0.1)
				(type default)
			)
			(layer "B.Fab")
		)
		(fp_line
			(start -0.67945 0.3048)
			(end -0.120396 0.3048)
			(stroke
				(width 0.1)
				(type default)
			)
			(layer "B.Fab")
		)
		(fp_line
			(start -0.12065 -0.3048)
			(end -0.67945 -0.3048)
			(stroke
				(width 0.1)
				(type default)
			)
			(layer "B.Fab")
		)
		(fp_line
			(start -0.12065 -0.2794)
			(end -0.12065 -0.3048)
			(stroke
				(width 0.1)
				(type default)
			)
			(layer "B.Fab")
		)
		(fp_line
			(start -0.120396 0.2794)
			(end 0.12065 0.2794)
			(stroke
				(width 0.1)
				(type default)
			)
			(layer "B.Fab")
		)
		(fp_line
			(start -0.120396 0.3048)
			(end -0.120396 0.2794)
			(stroke
				(width 0.1)
				(type default)
			)
			(layer "B.Fab")
		)
		(fp_line
			(start 0.12065 -0.305054)
			(end 0.12065 -0.2794)
			(stroke
				(width 0.1)
				(type default)
			)
			(layer "B.Fab")
		)
		(fp_line
			(start 0.12065 -0.2794)
			(end -0.12065 -0.2794)
			(stroke
				(width 0.1)
				(type default)
			)
			(layer "B.Fab")
		)
		(fp_line
			(start 0.12065 0.2794)
			(end 0.12065 0.3048)
			(stroke
				(width 0.1)
				(type default)
			)
			(layer "B.Fab")
		)
		(fp_line
			(start 0.12065 0.3048)
			(end 0.67945 0.3048)
			(stroke
				(width 0.1)
				(type default)
			)
			(layer "B.Fab")
		)
		(fp_line
			(start 0.67945 -0.305054)
			(end 0.12065 -0.305054)
			(stroke
				(width 0.1)
				(type default)
			)
			(layer "B.Fab")
		)
		(fp_line
			(start 0.67945 0.3048)
			(end 0.67945 -0.305054)
			(stroke
				(width 0.1)
				(type default)
			)
			(layer "B.Fab")
		)
		(pad "1" smd circle
			(at 0.40005 0 180)
			(size 0 0)
			(layers "B.Cu" "B.Mask" "B.Paste")
			(net "GND")
		)
		(pad "2" smd circle
			(at -0.40005 0 180)
			(size 0 0)
			(layers "B.Cu" "B.Mask" "B.Paste")
			(net "M_BMC_DDR4_MACT_N")
		)
	)
	(footprint ""
		(layer "B.Cu")
		(at 60.099702 -43.630342 180)
		(property "Reference" "C59"
			(at 0 0 0)
			(layer "B.SilkS")
			(hide yes)
			(effects
				(font
					(size 1.27 1.27)
				)
				(justify mirror)
			)
		)
		(property "Value" ""
			(at 0 0 0)
			(layer "B.Fab")
			(effects
				(font
					(size 1.27 1.27)
				)
				(justify mirror)
			)
		)
		(duplicate_pad_numbers_are_jumpers no)
		(fp_line
			(start 0.7874 0.4064)
			(end 0.7874 -0.4064)
			(stroke
				(width 0.1524)
				(type default)
			)
			(layer "B.SilkS")
		)
		(fp_line
			(start 0.7874 -0.4064)
			(end -0.7874 -0.4064)
			(stroke
				(width 0.1524)
				(type default)
			)
			(layer "B.SilkS")
		)
		(fp_line
			(start -0.7874 0.4064)
			(end 0.7874 0.4064)
			(stroke
				(width 0.1524)
				(type default)
			)
			(layer "B.SilkS")
		)
		(fp_line
			(start -0.7874 -0.4064)
			(end -0.7874 0.4064)
			(stroke
				(width 0.1524)
				(type default)
			)
			(layer "B.SilkS")
		)
		(fp_line
			(start 0.67945 0.3048)
			(end 0.67945 -0.305054)
			(stroke
				(width 0.1)
				(type default)
			)
			(layer "B.Fab")
		)
		(fp_line
			(start 0.67945 -0.305054)
			(end 0.12065 -0.305054)
			(stroke
				(width 0.1)
				(type default)
			)
			(layer "B.Fab")
		)
		(fp_line
			(start 0.12065 0.3048)
			(end 0.67945 0.3048)
			(stroke
				(width 0.1)
				(type default)
			)
			(layer "B.Fab")
		)
		(fp_line
			(start 0.12065 0.2794)
			(end 0.12065 0.3048)
			(stroke
				(width 0.1)
				(type default)
			)
			(layer "B.Fab")
		)
		(fp_line
			(start 0.12065 -0.2794)
			(end -0.12065 -0.2794)
			(stroke
				(width 0.1)
				(type default)
			)
			(layer "B.Fab")
		)
		(fp_line
			(start 0.12065 -0.305054)
			(end 0.12065 -0.2794)
			(stroke
				(width 0.1)
				(type default)
			)
			(layer "B.Fab")
		)
		(fp_line
			(start -0.120396 0.3048)
			(end -0.120396 0.2794)
			(stroke
				(width 0.1)
				(type default)
			)
			(layer "B.Fab")
		)
		(fp_line
			(start -0.120396 0.2794)
			(end 0.12065 0.2794)
			(stroke
				(width 0.1)
				(type default)
			)
			(layer "B.Fab")
		)
		(fp_line
			(start -0.12065 -0.2794)
			(end -0.12065 -0.3048)
			(stroke
				(width 0.1)
				(type default)
			)
			(layer "B.Fab")
		)
		(fp_line
			(start -0.12065 -0.3048)
			(end -0.67945 -0.3048)
			(stroke
				(width 0.1)
				(type default)
			)
			(layer "B.Fab")
		)
		(fp_line
			(start -0.67945 0.3048)
			(end -0.120396 0.3048)
			(stroke
				(width 0.1)
				(type default)
			)
			(layer "B.Fab")
		)
		(fp_line
			(start -0.67945 -0.3048)
			(end -0.67945 0.3048)
			(stroke
				(width 0.1)
				(type default)
			)
			(layer "B.Fab")
		)
		(pad "1" smd circle
			(at 0.40005 0)
			(size 0 0)
			(layers "B.Cu" "B.Mask" "B.Paste")
			(net "P1V0_STBY_PLAVDD")
		)
		(pad "2" smd circle
			(at -0.40005 0)
			(size 0 0)
			(layers "B.Cu" "B.Mask" "B.Paste")
			(net "GND")
		)
	)
)
